# T6G (Grand Teton) — schematic netlist excerpt (pin names and nets, part order shuffled) for the footprints in the layout excerpt that follows; sources: Cadence DE-HDL packaged netlist, KiCad conversion of 04192023_DAF0TMB3IC0_F0TG_MB_C_brd_V02_OCP.brd

PC1877  Q_CAP  47PF 50V 5% NPO  pkg 0402  page 189 : A = P5V_AUX_FB ; B = P5V_AUX
PR6010  Q_RES  10K 1% CHIP  pkg 0402LF  page 269 : A = P1V8_AUX_FB ; B = GND

(kicad_pcb
	(version 20260206)
	(generator "pcbnew")
	(generator_version "10.0")
	(general
		(thickness 1.6)
		(legacy_teardrops no)
	)
	(paper "A4")
	(title_block
		(title "04192023_DAF0TMB3IC0_F0TG_MB_C_brd_V02_OCP.brd")
		(comment 1 "Grand Teton / footprints 1777-1778 of 8354")
	)
	(layers
		(0 "F.Cu" signal "TOP")
		(4 "In1.Cu" signal "GND")
		(6 "In2.Cu" signal "IN1")
		(8 "In3.Cu" signal "GND1")
		(10 "In4.Cu" signal "IN2")
		(12 "In5.Cu" signal "GND2")
		(14 "In6.Cu" signal "IN3")
		(16 "In7.Cu" signal "GND3")
		(18 "In8.Cu" signal "VCC")
		(20 "In9.Cu" signal "VCC1")
		(22 "In10.Cu" signal "GND4")
		(24 "In11.Cu" signal "IN4")
		(26 "In12.Cu" signal "GND5")
		(28 "In13.Cu" signal "IN5")
		(30 "In14.Cu" signal "GND6")
		(32 "In15.Cu" signal "IN6")
		(34 "In16.Cu" signal "GND7")
		(2 "B.Cu" signal "BOTTOM")
		(9 "F.Adhes" user "F.Adhesive")
		(11 "B.Adhes" user "B.Adhesive")
		(13 "F.Paste" user "Package Geometry/Pastemask Top")
		(15 "B.Paste" user "Package Geometry/Pastemask Bottom")
		(5 "F.SilkS" user "Ref Des/Silkscreen Top")
		(7 "B.SilkS" user "Ref Des/Silkscreen Bottom")
		(1 "F.Mask" user "Board Geometry/Soldermask Top")
		(3 "B.Mask" user "Board Geometry/Soldermask Bottom")
		(17 "Dwgs.User" user "User.Drawings")
		(19 "Cmts.User" user "User.Comments")
		(21 "Eco1.User" user "User.Eco1")
		(23 "Eco2.User" user "User.Eco2")
		(25 "Edge.Cuts" user "Board Geometry/Outline")
		(27 "Margin" user)
		(31 "F.CrtYd" user "Package Geometry/Place Bound Top")
		(29 "B.CrtYd" user "Package Geometry/Place Bound Bottom")
		(35 "F.Fab" user "Ref Des/Assembly Top")
		(33 "B.Fab" user "Ref Des/Assembly Bottom")
	)
	(footprint ""
		(layer "F.Cu")
		(at 407.742644 -139.362942 -90)
		(property "Reference" "PC1877"
			(at 0 0 270)
			(layer "F.SilkS")
			(hide yes)
			(effects
				(font
					(size 1.27 1.27)
				)
			)
		)
		(property "Value" ""
			(at 0 0 270)
			(layer "F.Fab")
			(effects
				(font
					(size 1.27 1.27)
				)
			)
		)
		(duplicate_pad_numbers_are_jumpers no)
		(fp_line
			(start -0.7874 0.4064)
			(end -0.7874 -0.4064)
			(stroke
				(width 0.1524)
				(type default)
			)
			(layer "F.SilkS")
		)
		(fp_line
			(start 0.7874 0.4064)
			(end -0.7874 0.4064)
			(stroke
				(width 0.1524)
				(type default)
			)
			(layer "F.SilkS")
		)
		(fp_line
			(start -0.7874 -0.4064)
			(end 0.7874 -0.4064)
			(stroke
				(width 0.1524)
				(type default)
			)
			(layer "F.SilkS")
		)
		(fp_line
			(start 0.7874 -0.4064)
			(end 0.7874 0.4064)
			(stroke
				(width 0.1524)
				(type default)
			)
			(layer "F.SilkS")
		)
		(fp_line
			(start -0.67945 0.3048)
			(end -0.67945 -0.305054)
			(stroke
				(width 0.1)
				(type default)
			)
			(layer "F.Fab")
		)
		(fp_line
			(start -0.12065 0.3048)
			(end -0.67945 0.3048)
			(stroke
				(width 0.1)
				(type default)
			)
			(layer "F.Fab")
		)
		(fp_line
			(start 0.120396 0.3048)
			(end 0.120396 0.2794)
			(stroke
				(width 0.1)
				(type default)
			)
			(layer "F.Fab")
		)
		(fp_line
			(start 0.67945 0.3048)
			(end 0.120396 0.3048)
			(stroke
				(width 0.1)
				(type default)
			)
			(layer "F.Fab")
		)
		(fp_line
			(start -0.12065 0.2794)
			(end -0.12065 0.3048)
			(stroke
				(width 0.1)
				(type default)
			)
			(layer "F.Fab")
		)
		(fp_line
			(start 0.120396 0.2794)
			(end -0.12065 0.2794)
			(stroke
				(width 0.1)
				(type default)
			)
			(layer "F.Fab")
		)
		(fp_line
			(start -0.12065 -0.2794)
			(end 0.12065 -0.2794)
			(stroke
				(width 0.1)
				(type default)
			)
			(layer "F.Fab")
		)
		(fp_line
			(start 0.12065 -0.2794)
			(end 0.12065 -0.3048)
			(stroke
				(width 0.1)
				(type default)
			)
			(layer "F.Fab")
		)
		(fp_line
			(start 0.12065 -0.3048)
			(end 0.67945 -0.3048)
			(stroke
				(width 0.1)
				(type default)
			)
			(layer "F.Fab")
		)
		(fp_line
			(start 0.67945 -0.3048)
			(end 0.67945 0.3048)
			(stroke
				(width 0.1)
				(type default)
			)
			(layer "F.Fab")
		)
		(fp_line
			(start -0.67945 -0.305054)
			(end -0.12065 -0.305054)
			(stroke
				(width 0.1)
				(type default)
			)
			(layer "F.Fab")
		)
		(fp_line
			(start -0.12065 -0.305054)
			(end -0.12065 -0.2794)
			(stroke
				(width 0.1)
				(type default)
			)
			(layer "F.Fab")
		)
		(pad "1" smd circle
			(at -0.40005 0 270)
			(size 0 0)
			(layers "F.Cu" "F.Mask" "F.Paste")
			(net "P5V_AUX_FB")
		)
		(pad "2" smd circle
			(at 0.40005 0 270)
			(size 0 0)
			(layers "F.Cu" "F.Mask" "F.Paste")
			(net "P5V_AUX")
		)
	)
	(footprint ""
		(layer "F.Cu")
		(at 142.729712 -75.582272 -0.054)
		(property "Reference" "PR6010"
			(at 0 0 359.946)
			(layer "F.SilkS")
			(hide yes)
			(effects
				(font
					(size 1.27 1.27)
				)
			)
		)
		(property "Value" ""
			(at 0 0 359.946)
			(layer "F.Fab")
			(effects
				(font
					(size 1.27 1.27)
				)
			)
		)
		(duplicate_pad_numbers_are_jumpers no)
		(fp_line
			(start -0.787525 0.40638)
			(end -0.787275 -0.40642)
			(stroke
				(width 0.1524)
				(type default)
			)
			(layer "F.SilkS")
		)
		(fp_line
			(start -0.787275 -0.40642)
			(end 0.787525 -0.40638)
			(stroke
				(width 0.1524)
				(type default)
			)
			(layer "F.SilkS")
		)
		(fp_line
			(start 0.787275 0.40642)
			(end -0.787525 0.40638)
			(stroke
				(width 0.1524)
				(type default)
			)
			(layer "F.SilkS")
		)
		(fp_line
			(start 0.787525 -0.40638)
			(end 0.787275 0.40642)
			(stroke
				(width 0.1524)
				(type default)
			)
			(layer "F.SilkS")
		)
		(fp_line
			(start -0.679417 0.304678)
			(end -0.679484 -0.305176)
			(stroke
				(width 0.1)
				(type default)
			)
			(layer "F.Fab")
		)
		(fp_line
			(start -0.679484 -0.305176)
			(end -0.120683 -0.30494)
			(stroke
				(width 0.1)
				(type default)
			)
			(layer "F.Fab")
		)
		(fp_line
			(start -0.120641 0.279514)
			(end -0.120617 0.304914)
			(stroke
				(width 0.1)
				(type default)
			)
			(layer "F.Fab")
		)
		(fp_line
			(start -0.120617 0.304914)
			(end -0.679417 0.304678)
			(stroke
				(width 0.1)
				(type default)
			)
			(layer "F.Fab")
		)
		(fp_line
			(start -0.120683 -0.30494)
			(end -0.120659 -0.279286)
			(stroke
				(width 0.1)
				(type default)
			)
			(layer "F.Fab")
		)
		(fp_line
			(start -0.120659 -0.279286)
			(end 0.120641 -0.279514)
			(stroke
				(width 0.1)
				(type default)
			)
			(layer "F.Fab")
		)
		(fp_line
			(start 0.120405 0.279287)
			(end -0.120641 0.279514)
			(stroke
				(width 0.1)
				(type default)
			)
			(layer "F.Fab")
		)
		(fp_line
			(start 0.120429 0.304687)
			(end 0.120405 0.279287)
			(stroke
				(width 0.1)
				(type default)
			)
			(layer "F.Fab")
		)
		(fp_line
			(start 0.120617 -0.304914)
			(end 0.679417 -0.304678)
			(stroke
				(width 0.1)
				(type default)
			)
			(layer "F.Fab")
		)
		(fp_line
			(start 0.120641 -0.279514)
			(end 0.120617 -0.304914)
			(stroke
				(width 0.1)
				(type default)
			)
			(layer "F.Fab")
		)
		(fp_line
			(start 0.679484 0.304922)
			(end 0.120429 0.304687)
			(stroke
				(width 0.1)
				(type default)
			)
			(layer "F.Fab")
		)
		(fp_line
			(start 0.679417 -0.304678)
			(end 0.679484 0.304922)
			(stroke
				(width 0.1)
				(type default)
			)
			(layer "F.Fab")
		)
		(pad "1" smd circle
			(at -0.40005 0 359.946)
			(size 0 0)
			(layers "F.Cu" "F.Mask" "F.Paste")
			(net "P1V8_AUX_FB")
		)
		(pad "2" smd circle
			(at 0.40005 0 359.946)
			(size 0 0)
			(layers "F.Cu" "F.Mask" "F.Paste")
			(net "GND")
		)
	)
)
